# T6G (Grand Teton) — schematic netlist excerpt (pin names and nets, part order shuffled) for the footprints in the layout excerpt that follows; sources: Cadence DE-HDL packaged netlist, KiCad conversion of 04192023_DAF0TMB3IC0_F0TG_MB_C_brd_V02_OCP.brd

J33  SCONN288_DDR506112002KQ  IO  pkg DDR288S_1-1VXC  page 103
  VIN_BULK0  = P12V_MEM_CPU1
  RFU0  = NC
  VIN_MGMT  = P3V3_AUX
  HSCL  = I3C_SPD_DDRF_CPU1_SCL
  HSDA  = I3C_SPD_DDRF_CPU1_SDA
  VSS0  = GND
  DQ0_A  = M_F_CPU1_SA_DQ<0>
  VSS1  = GND
  DQ1_A  = M_F_CPU1_SA_DQ<1>
  VSS2  = GND
  DQS0_A_T  = M_F_CPU1_SA_DQS_DP<0>
  DQS0_A_C  = M_F_CPU1_SA_DQS_DN<0>
  VSS3  = GND
  DQ4_A  = M_F_CPU1_SA_DQ<4>
  VSS4  = GND
  DQ5_A  = M_F_CPU1_SA_DQ<5>
  VSS5  = GND
  DQ8_A  = M_F_CPU1_SA_DQ<8>
  VSS6  = GND
  DQ9_A  = M_F_CPU1_SA_DQ<9>
  VSS7  = GND
  DQS1_A_T  = M_F_CPU1_SA_DQS_DP<1>
  DQS1_A_C  = M_F_CPU1_SA_DQS_DN<1>
  VSS8  = GND
  DQ12_A  = M_F_CPU1_SA_DQ<12>
  VSS9  = GND
  DQ13_A  = M_F_CPU1_SA_DQ<13>
  VSS10  = GND
  DQ16_A  = M_F_CPU1_SA_DQ<16>
  VSS11  = GND
  DQ17_A  = M_F_CPU1_SA_DQ<17>
  VSS12  = GND
  DQS2_A_T  = M_F_CPU1_SA_DQS_DP<2>
  DQS2_A_C  = M_F_CPU1_SA_DQS_DN<2>
  VSS13  = GND
  DQ20_A  = M_F_CPU1_SA_DQ<20>
  VSS14  = GND
  DQ21_A  = M_F_CPU1_SA_DQ<21>
  VSS15  = GND
  DQ24_A  = M_F_CPU1_SA_DQ<24>
  VSS16  = GND
  DQ25_A  = M_F_CPU1_SA_DQ<25>
  VSS17  = GND
  DQS3_A_T  = M_F_CPU1_SA_DQS_DP<3>
  DQS3_A_C  = M_F_CPU1_SA_DQS_DN<3>
  VSS18  = GND
  DQ28_A  = M_F_CPU1_SA_DQ<28>
  VSS19  = GND
  DQ29_A  = M_F_CPU1_SA_DQ<29>
  VSS20  = GND
  CB0_A  = M_F_CPU1_SA_CB<0>
  VSS21  = GND
  CB1_A  = M_F_CPU1_SA_CB<1>
  VSS22  = GND
  DQS4_A_T  = M_F_CPU1_SA_DQS_DP<4>
  DQS4_A_C  = M_F_CPU1_SA_DQS_DN<4>
  VSS23  = GND
  CB4_A  = M_F_CPU1_SA_CB<4>
  VSS24  = GND
  CB5_A  = M_F_CPU1_SA_CB<5>
  VSS25  = GND
  ALERT_N  = M_F_CPU1_ALERT_N
  VSS26  = GND
  CS0_A_N  = M_F_CPU1_SA_CS_N<0>
  VSS27  = GND
  CA0_A  = M_F_CPU1_SA_CA<0>
  VSS28  = GND
  CA2_A  = M_F_CPU1_SA_CA<2>
  VSS29  = GND
  CA4_A  = M_F_CPU1_SA_CA<4>
  VSS30  = GND
  CA6_A  = M_F_CPU1_SA_CA<6>
  VSS31  = GND
  PAR_A  = M_F_CPU1_SA_PAR
  VSS32  = GND
  CA0_B  = M_F_CPU1_SB_CA<0>
  VSS33  = GND
  CA2_B  = M_F_CPU1_SB_CA<2>
  VSS34  = GND
  CA4_B  = M_F_CPU1_SB_CA<4>
  VSS35  = GND
  CA6_B  = M_F_CPU1_SB_CA<6>
  VSS36  = GND
  CS0_B_N  = M_F_CPU1_SB_CS_N<0>
  VSS37  = GND
  \lbd||rsp_a_n\  = M_F_CPU1_SA_RSP<0>
  \lbs||rsp_b_n\  = M_F_CPU1_SB_RSP<0>
  VSS38  = GND
  CB4_B  = M_F_CPU1_SB_CB<4>
  VSS39  = GND
  CB5_B  = M_F_CPU1_SB_CB<5>
  VSS40  = GND
  \dqs9_b_t||tdqs9_b_t||dbi4_b_n\  = M_F_CPU1_SB_DQS_DP<9>
  \dqs9_b_c||tdqs9_b_c\  = M_F_CPU1_SB_DQS_DN<9>
  VSS41  = GND
  CB0_B  = M_F_CPU1_SB_CB<0>
  VSS42  = GND
  CB1_B  = M_F_CPU1_SB_CB<1>
  VSS43  = GND
  DQ0_B  = M_F_CPU1_SB_DQ<0>
  VSS44  = GND
  DQ1_B  = M_F_CPU1_SB_DQ<1>
  VSS45  = GND
  DQS0_B_T  = M_F_CPU1_SB_DQS_DP<0>
  DQS0_B_C  = M_F_CPU1_SB_DQS_DN<0>
  VSS46  = GND
  DQ4_B  = M_F_CPU1_SB_DQ<4>
  VSS47  = GND
  DQ5_B  = M_F_CPU1_SB_DQ<5>
  VSS48  = GND
  DQ8_B  = M_F_CPU1_SB_DQ<8>
  VSS49  = GND
  DQ9_B  = M_F_CPU1_SB_DQ<9>
  VSS50  = GND
  DQS1_B_T  = M_F_CPU1_SB_DQS_DP<1>
  DQS1_B_C  = M_F_CPU1_SB_DQS_DN<1>
  VSS51  = GND
  DQ12_B  = M_F_CPU1_SB_DQ<12>
  VSS52  = GND
  DQ13_B  = M_F_CPU1_SB_DQ<13>
  VSS53  = GND
  DQ16_B  = M_F_CPU1_SB_DQ<16>
  VSS54  = GND
  DQ17_B  = M_F_CPU1_SB_DQ<17>
  VSS55  = GND
  DQS2_B_T  = M_F_CPU1_SB_DQS_DP<2>
  DQS2_B_C  = M_F_CPU1_SB_DQS_DN<2>
  VSS56  = GND
  DQ20_B  = M_F_CPU1_SB_DQ<20>
  VSS57  = GND
  DQ21_B  = M_F_CPU1_SB_DQ<21>
  VSS58  = GND
  DQ24_B  = M_F_CPU1_SB_DQ<24>
  VSS59  = GND
  DQ25_B  = M_F_CPU1_SB_DQ<25>
  VSS60  = GND
  DQS3_B_T  = M_F_CPU1_SB_DQS_DP<3>
  DQS3_B_C  = M_F_CPU1_SB_DQS_DN<3>
  VSS61  = GND
  DQ28_B  = M_F_CPU1_SB_DQ<28>
  VSS62  = GND
  DQ29_B  = M_F_CPU1_SB_DQ<29>
  VSS63  = GND
  RFU1  = NC
  VIN_BULK1  = P12V_MEM_CPU1
  VIN_BULK2  = P12V_MEM_CPU1
  \pwr_good||fail_n\  = PWRGD_CHF_CPU1_DIMM
  HAS  = PD_CHF_CPU1_DIMM_SAA
  RFU2  = NC
  RFU3  = NC
  VSS64  = GND
  DQ2_A  = M_F_CPU1_SA_DQ<2>
  VSS65  = GND
  DQ3_A  = M_F_CPU1_SA_DQ<3>
  VSS66  = GND
  \dqs5_a_c||tdqs5_a_c||dqs5_a_t||tdqs5_a_t\  = M_F_CPU1_SA_DQS_DN<5>
  \dqs5_a_t||tdqs5_a_t\  = M_F_CPU1_SA_DQS_DP<5>
  VSS67  = GND
  DQ6_A  = M_F_CPU1_SA_DQ<6>
  VSS68  = GND
  DQ7_A  = M_F_CPU1_SA_DQ<7>
  VSS69  = GND
  DQ10_A  = M_F_CPU1_SA_DQ<10>
  VSS70  = GND
  DQ11_A  = M_F_CPU1_SA_DQ<11>
  VSS71  = GND
  \dqs6_a_c||tdqs6_a_c||dqs6_a_t||tdqs6_a_t\  = M_F_CPU1_SA_DQS_DN<6>
  \dqs6_a_t||tdqs6_a_t\  = M_F_CPU1_SA_DQS_DP<6>
  VSS72  = GND
  DQ14_A  = M_F_CPU1_SA_DQ<14>
  VSS73  = GND
  DQ15_A  = M_F_CPU1_SA_DQ<15>
  VSS74  = GND
  DQ18_A  = M_F_CPU1_SA_DQ<18>
  VSS75  = GND
  DQ19_A  = M_F_CPU1_SA_DQ<19>
  VSS76  = GND
  \dqs7_a_c||tdqs7_a_c\  = M_F_CPU1_SA_DQS_DN<7>
  \dqs7_a_t||tdqs7_a_t\  = M_F_CPU1_SA_DQS_DP<7>
  VSS77  = GND
  DQ22_A  = M_F_CPU1_SA_DQ<22>
  VSS78  = GND
  DQ23_A  = M_F_CPU1_SA_DQ<23>
  VSS79  = GND
  DQ26_A  = M_F_CPU1_SA_DQ<26>
  VSS80  = GND
  DQ27_A  = M_F_CPU1_SA_DQ<27>
  VSS81  = GND
  \dqs8_a_c||tdqs8_a_c\  = M_F_CPU1_SA_DQS_DN<8>
  \dqs8_a_t||tdqs8_a_t\  = M_F_CPU1_SA_DQS_DP<8>
  VSS82  = GND
  DQ30_A  = M_F_CPU1_SA_DQ<30>
  VSS83  = GND
  DQ31_A  = M_F_CPU1_SA_DQ<31>
  VSS84  = GND
  CB2_A  = M_F_CPU1_SA_CB<2>
  VSS85  = GND
  CB3_A  = M_F_CPU1_SA_CB<3>
  VSS86  = GND
  \dqs9_a_c||tdqs9_a_c\  = M_F_CPU1_SA_DQS_DN<9>
  \dqs9_a_t||tdqs9_a_t\  = M_F_CPU1_SA_DQS_DP<9>
  VSS87  = GND
  CB6_A  = M_F_CPU1_SA_CB<6>
  VSS88  = GND
  CB7_A  = M_F_CPU1_SA_CB<7>
  VSS89  = GND
  RESET_N  = M_F_CPU1_RESET_N
  VSS90  = GND
  CS1_A_N  = M_F_CPU1_SA_CS_N<1>
  VSS91  = GND
  CA1_A  = M_F_CPU1_SA_CA<1>
  VSS92  = GND
  CA3_A  = M_F_CPU1_SA_CA<3>
  VSS93  = GND
  CA5_A  = M_F_CPU1_SA_CA<5>
  VSS94  = GND
  CK_T  = M_F_CPU1_CLK_DP<0>
  CK_C  = M_F_CPU1_CLK_DN<0>
  VSS95  = GND
  RFU4  = NC
  CA1_B  = M_F_CPU1_SB_CA<1>
  VSS96  = GND
  CA3_B  = M_F_CPU1_SB_CA<3>
  VSS97  = GND
  CA5_B  = M_F_CPU1_SB_CA<5>
  VSS98  = GND
  PAR_B  = M_F_CPU1_SB_PAR
  VSS99  = GND
  CS1_B_N  = M_F_CPU1_SB_CS_N<1>
  VSS100  = GND
  RFU5  = NC
  RFU6  = NC
  VSS101  = GND
  CB6_B  = M_F_CPU1_SB_CB<6>
  VSS102  = GND
  CB7_B  = M_F_CPU1_SB_CB<7>
  VSS103  = GND
  DQS4_B_C  = M_F_CPU1_SB_DQS_DN<4>
  DQS4_B_T  = M_F_CPU1_SB_DQS_DP<4>
  VSS104  = GND
  CB2_B  = M_F_CPU1_SB_CB<2>
  VSS105  = GND
  CB3_B  = M_F_CPU1_SB_CB<3>
  VSS106  = GND
  DQ2_B  = M_F_CPU1_SB_DQ<2>
  VSS107  = GND
  DQ3_B  = M_F_CPU1_SB_DQ<3>
  VSS108  = GND
  \dqs5_b_c||tdqs5_b_c\  = M_F_CPU1_SB_DQS_DN<5>
  \dqs5_b_t||tdqs5_b_t\  = M_F_CPU1_SB_DQS_DP<5>
  VSS109  = GND
  DQ6_B  = M_F_CPU1_SB_DQ<6>
  VSS110  = GND
  DQ7_B  = M_F_CPU1_SB_DQ<7>
  VSS111  = GND
  DQ10_B  = M_F_CPU1_SB_DQ<10>
  VSS112  = GND
  DQ11_B  = M_F_CPU1_SB_DQ<11>
  VSS113  = GND
  \dqs6_b_c||tdqs6_b_c\  = M_F_CPU1_SB_DQS_DN<6>
  \dqs6_b_t||tdqs6_b_t\  = M_F_CPU1_SB_DQS_DP<6>
  VSS114  = GND
  DQ14_B  = M_F_CPU1_SB_DQ<14>
  VSS115  = GND
  DQ15_B  = M_F_CPU1_SB_DQ<15>
  VSS116  = GND
  DQ18_B  = M_F_CPU1_SB_DQ<18>
  VSS117  = GND
  DQ19_B  = M_F_CPU1_SB_DQ<19>
  VSS118  = GND
  \dqs7_b_c||tdqs7_b_c\  = M_F_CPU1_SB_DQS_DN<7>
  \dqs7_b_t||tdqs7_b_t\  = M_F_CPU1_SB_DQS_DP<7>
  VSS119  = GND
  DQ22_B  = M_F_CPU1_SB_DQ<22>
  VSS120  = GND
  DQ23_B  = M_F_CPU1_SB_DQ<23>
  VSS121  = GND
  DQ26_B  = M_F_CPU1_SB_DQ<26>
  VSS122  = GND
  DQ27_B  = M_F_CPU1_SB_DQ<27>
  VSS123  = GND
  \dqs8_b_c||tdqs8_b_c\  = M_F_CPU1_SB_DQS_DN<8>
  \dqs8_b_t||tdqs8_b_t\  = M_F_CPU1_SB_DQS_DP<8>
  VSS124  = GND
  DQ30_B  = M_F_CPU1_SB_DQ<30>
  VSS125  = GND
  DQ31_B  = M_F_CPU1_SB_DQ<31>
  VSS126  = GND
  G1  = GND
  G2  = GND
  G3  = GND

(kicad_pcb
	(version 20260206)
	(generator "pcbnew")
	(generator_version "10.0")
	(general
		(thickness 1.6)
		(legacy_teardrops no)
	)
	(paper "A4")
	(title_block
		(title "04192023_DAF0TMB3IC0_F0TG_MB_C_brd_V02_OCP.brd")
		(comment 1 "Grand Teton / footprint 4248 of 8354 (J33), pads 139-184 of 291")
	)
	(layers
		(0 "F.Cu" signal "TOP")
		(4 "In1.Cu" signal "GND")
		(6 "In2.Cu" signal "IN1")
		(8 "In3.Cu" signal "GND1")
		(10 "In4.Cu" signal "IN2")
		(12 "In5.Cu" signal "GND2")
		(14 "In6.Cu" signal "IN3")
		(16 "In7.Cu" signal "GND3")
		(18 "In8.Cu" signal "VCC")
		(20 "In9.Cu" signal "VCC1")
		(22 "In10.Cu" signal "GND4")
		(24 "In11.Cu" signal "IN4")
		(26 "In12.Cu" signal "GND5")
		(28 "In13.Cu" signal "IN5")
		(30 "In14.Cu" signal "GND6")
		(32 "In15.Cu" signal "IN6")
		(34 "In16.Cu" signal "GND7")
		(2 "B.Cu" signal "BOTTOM")
		(9 "F.Adhes" user "F.Adhesive")
		(11 "B.Adhes" user "B.Adhesive")
		(13 "F.Paste" user "Package Geometry/Pastemask Top")
		(15 "B.Paste" user "Package Geometry/Pastemask Bottom")
		(5 "F.SilkS" user "Ref Des/Silkscreen Top")
		(7 "B.SilkS" user "Ref Des/Silkscreen Bottom")
		(1 "F.Mask" user "Board Geometry/Soldermask Top")
		(3 "B.Mask" user "Board Geometry/Soldermask Bottom")
		(17 "Dwgs.User" user "User.Drawings")
		(19 "Cmts.User" user "User.Comments")
		(21 "Eco1.User" user "User.Eco1")
		(23 "Eco2.User" user "User.Eco2")
		(25 "Edge.Cuts" user "Board Geometry/Outline")
		(27 "Margin" user)
		(31 "F.CrtYd" user "Package Geometry/Place Bound Top")
		(29 "B.CrtYd" user "Package Geometry/Place Bound Bottom")
		(35 "F.Fab" user "Ref Des/Assembly Top")
		(33 "B.Fab" user "Ref Des/Assembly Bottom")
	)
	(footprint ""
		(layer "F.Cu")
		(at 19.658076 -255.560322 180)
		(property "Reference" "J33"
			(at -1.25984 -82.079846 0)
			(unlocked yes)
			(layer "F.SilkS")
			(effects
				(font
					(size 0.7874 0.5842)
					(thickness 0.1524)
				)
			)
		)
		(property "Value" ""
			(at 0 0 180)
			(layer "F.Fab")
			(effects
				(font
					(size 1.27 1.27)
				)
			)
		)
		(duplicate_pad_numbers_are_jumpers no)
		(pad "139" smd rect
			(at -2.050034 59.075066 90)
			(size 0.519938 1.4986)
			(layers "F.Cu" "F.Mask" "F.Paste")
			(net "GND")
		)
		(pad "140" smd rect
			(at -2.050034 59.92495 90)
			(size 0.519938 1.4986)
			(layers "F.Cu" "F.Mask" "F.Paste")
			(net "M_F_CPU1_SB_DQ<28>")
		)
		(pad "141" smd rect
			(at -2.050034 60.775088 90)
			(size 0.519938 1.4986)
			(layers "F.Cu" "F.Mask" "F.Paste")
			(net "GND")
		)
		(pad "142" smd rect
			(at -2.050034 61.624972 90)
			(size 0.519938 1.4986)
			(layers "F.Cu" "F.Mask" "F.Paste")
			(net "M_F_CPU1_SB_DQ<29>")
		)
		(pad "143" smd rect
			(at -2.050034 62.47511 90)
			(size 0.519938 1.4986)
			(layers "F.Cu" "F.Mask" "F.Paste")
			(net "GND")
		)
		(pad "144" smd rect
			(at -2.050034 63.324994 90)
			(size 0.519938 1.4986)
			(layers "F.Cu" "F.Mask" "F.Paste")
			(net "Net_2327")
		)
		(pad "145" smd rect
			(at 2.050034 -63.324994 90)
			(size 0.519938 1.4986)
			(layers "F.Cu" "F.Mask" "F.Paste")
			(net "P12V_MEM_CPU1")
		)
		(pad "146" smd rect
			(at 2.050034 -62.47511 90)
			(size 0.519938 1.4986)
			(layers "F.Cu" "F.Mask" "F.Paste")
			(net "P12V_MEM_CPU1")
		)
		(pad "147" smd rect
			(at 2.050034 -61.624972 90)
			(size 0.519938 1.4986)
			(layers "F.Cu" "F.Mask" "F.Paste")
			(net "PWRGD_CHF_CPU1_DIMM")
		)
		(pad "148" smd rect
			(at 2.050034 -60.775088 90)
			(size 0.519938 1.4986)
			(layers "F.Cu" "F.Mask" "F.Paste")
			(net "PD_CHF_CPU1_DIMM_SAA")
		)
		(pad "149" smd rect
			(at 2.050034 -59.92495 90)
			(size 0.519938 1.4986)
			(layers "F.Cu" "F.Mask" "F.Paste")
			(net "Net_2328")
		)
		(pad "150" smd rect
			(at 2.050034 -59.075066 90)
			(size 0.519938 1.4986)
			(layers "F.Cu" "F.Mask" "F.Paste")
			(net "Net_2329")
		)
		(pad "151" smd rect
			(at 2.050034 -58.224928 90)
			(size 0.519938 1.4986)
			(layers "F.Cu" "F.Mask" "F.Paste")
			(net "GND")
		)
		(pad "152" smd rect
			(at 2.050034 -57.375044 90)
			(size 0.519938 1.4986)
			(layers "F.Cu" "F.Mask" "F.Paste")
			(net "M_F_CPU1_SA_DQ<2>")
		)
		(pad "153" smd rect
			(at 2.050034 -56.524906 90)
			(size 0.519938 1.4986)
			(layers "F.Cu" "F.Mask" "F.Paste")
			(net "GND")
		)
		(pad "154" smd rect
			(at 2.050034 -55.675022 90)
			(size 0.519938 1.4986)
			(layers "F.Cu" "F.Mask" "F.Paste")
			(net "M_F_CPU1_SA_DQ<3>")
		)
		(pad "155" smd rect
			(at 2.050034 -54.824884 90)
			(size 0.519938 1.4986)
			(layers "F.Cu" "F.Mask" "F.Paste")
			(net "GND")
		)
		(pad "156" smd rect
			(at 2.050034 -53.975 90)
			(size 0.519938 1.4986)
			(layers "F.Cu" "F.Mask" "F.Paste")
			(net "M_F_CPU1_SA_DQS_DN<5>")
		)
		(pad "157" smd rect
			(at 2.050034 -53.125116 90)
			(size 0.519938 1.4986)
			(layers "F.Cu" "F.Mask" "F.Paste")
			(net "M_F_CPU1_SA_DQS_DP<5>")
		)
		(pad "158" smd rect
			(at 2.050034 -52.274978 90)
			(size 0.519938 1.4986)
			(layers "F.Cu" "F.Mask" "F.Paste")
			(net "GND")
		)
		(pad "159" smd rect
			(at 2.050034 -51.425094 90)
			(size 0.519938 1.4986)
			(layers "F.Cu" "F.Mask" "F.Paste")
			(net "M_F_CPU1_SA_DQ<6>")
		)
		(pad "160" smd rect
			(at 2.050034 -50.574956 90)
			(size 0.519938 1.4986)
			(layers "F.Cu" "F.Mask" "F.Paste")
			(net "GND")
		)
		(pad "161" smd rect
			(at 2.050034 -49.725072 90)
			(size 0.519938 1.4986)
			(layers "F.Cu" "F.Mask" "F.Paste")
			(net "M_F_CPU1_SA_DQ<7>")
		)
		(pad "162" smd rect
			(at 2.050034 -48.874934 90)
			(size 0.519938 1.4986)
			(layers "F.Cu" "F.Mask" "F.Paste")
			(net "GND")
		)
		(pad "163" smd rect
			(at 2.050034 -48.02505 90)
			(size 0.519938 1.4986)
			(layers "F.Cu" "F.Mask" "F.Paste")
			(net "M_F_CPU1_SA_DQ<10>")
		)
		(pad "164" smd rect
			(at 2.050034 -47.174912 90)
			(size 0.519938 1.4986)
			(layers "F.Cu" "F.Mask" "F.Paste")
			(net "GND")
		)
		(pad "165" smd rect
			(at 2.050034 -46.325028 90)
			(size 0.519938 1.4986)
			(layers "F.Cu" "F.Mask" "F.Paste")
			(net "M_F_CPU1_SA_DQ<11>")
		)
		(pad "166" smd rect
			(at 2.050034 -45.47489 90)
			(size 0.519938 1.4986)
			(layers "F.Cu" "F.Mask" "F.Paste")
			(net "GND")
		)
		(pad "167" smd rect
			(at 2.050034 -44.625006 90)
			(size 0.519938 1.4986)
			(layers "F.Cu" "F.Mask" "F.Paste")
			(net "M_F_CPU1_SA_DQS_DN<6>")
		)
		(pad "168" smd rect
			(at 2.050034 -43.775122 90)
			(size 0.519938 1.4986)
			(layers "F.Cu" "F.Mask" "F.Paste")
			(net "M_F_CPU1_SA_DQS_DP<6>")
		)
		(pad "169" smd rect
			(at 2.050034 -42.924984 90)
			(size 0.519938 1.4986)
			(layers "F.Cu" "F.Mask" "F.Paste")
			(net "GND")
		)
		(pad "170" smd rect
			(at 2.050034 -42.0751 90)
			(size 0.519938 1.4986)
			(layers "F.Cu" "F.Mask" "F.Paste")
			(net "M_F_CPU1_SA_DQ<14>")
		)
		(pad "171" smd rect
			(at 2.050034 -41.224962 90)
			(size 0.519938 1.4986)
			(layers "F.Cu" "F.Mask" "F.Paste")
			(net "GND")
		)
		(pad "172" smd rect
			(at 2.050034 -40.375078 90)
			(size 0.519938 1.4986)
			(layers "F.Cu" "F.Mask" "F.Paste")
			(net "M_F_CPU1_SA_DQ<15>")
		)
		(pad "173" smd rect
			(at 2.050034 -39.52494 90)
			(size 0.519938 1.4986)
			(layers "F.Cu" "F.Mask" "F.Paste")
			(net "GND")
		)
		(pad "174" smd rect
			(at 2.050034 -38.675056 90)
			(size 0.519938 1.4986)
			(layers "F.Cu" "F.Mask" "F.Paste")
			(net "M_F_CPU1_SA_DQ<18>")
		)
		(pad "175" smd rect
			(at 2.050034 -37.824918 90)
			(size 0.519938 1.4986)
			(layers "F.Cu" "F.Mask" "F.Paste")
			(net "GND")
		)
		(pad "176" smd rect
			(at 2.050034 -36.975034 90)
			(size 0.519938 1.4986)
			(layers "F.Cu" "F.Mask" "F.Paste")
			(net "M_F_CPU1_SA_DQ<19>")
		)
		(pad "177" smd rect
			(at 2.050034 -36.124896 90)
			(size 0.519938 1.4986)
			(layers "F.Cu" "F.Mask" "F.Paste")
			(net "GND")
		)
		(pad "178" smd rect
			(at 2.050034 -35.275012 90)
			(size 0.519938 1.4986)
			(layers "F.Cu" "F.Mask" "F.Paste")
			(net "M_F_CPU1_SA_DQS_DN<7>")
		)
		(pad "179" smd rect
			(at 2.050034 -34.425128 90)
			(size 0.519938 1.4986)
			(layers "F.Cu" "F.Mask" "F.Paste")
			(net "M_F_CPU1_SA_DQS_DP<7>")
		)
		(pad "180" smd rect
			(at 2.050034 -33.57499 90)
			(size 0.519938 1.4986)
			(layers "F.Cu" "F.Mask" "F.Paste")
			(net "GND")
		)
		(pad "181" smd rect
			(at 2.050034 -32.725106 90)
			(size 0.519938 1.4986)
			(layers "F.Cu" "F.Mask" "F.Paste")
			(net "M_F_CPU1_SA_DQ<22>")
		)
		(pad "182" smd rect
			(at 2.050034 -31.874968 90)
			(size 0.519938 1.4986)
			(layers "F.Cu" "F.Mask" "F.Paste")
			(net "GND")
		)
		(pad "183" smd rect
			(at 2.050034 -31.025084 90)
			(size 0.519938 1.4986)
			(layers "F.Cu" "F.Mask" "F.Paste")
			(net "M_F_CPU1_SA_DQ<23>")
		)
		(pad "184" smd rect
			(at 2.050034 -30.174946 90)
			(size 0.519938 1.4986)
			(layers "F.Cu" "F.Mask" "F.Paste")
			(net "GND")
		)
	)
)
